(kicad_pcb
	(version 20241229)
	(generator "pcbnew")
	(generator_version "9.0")
	(general
		(thickness 1.6642)
		(legacy_teardrops no)
	)
	(paper "A3")
	(title_block
		(title "PolarFire SoM")
		(date "2025-07-22")
		(rev "1.1.4")
		(company "Antmicro Ltd")
		(comment 1 "www.antmicro.com")
		(comment 9 "footprints 318-321 of 470")
	)
	(layers
		(0 "F.Cu" mixed)
		(4 "In1.Cu" power)
		(6 "In2.Cu" signal)
		(8 "In3.Cu" power)
		(10 "In4.Cu" signal)
		(12 "In5.Cu" power)
		(14 "In6.Cu" power)
		(16 "In7.Cu" signal)
		(18 "In8.Cu" power)
		(20 "In9.Cu" signal)
		(22 "In10.Cu" power)
		(24 "In11.Cu" signal)
		(26 "In12.Cu" signal)
		(2 "B.Cu" mixed)
		(9 "F.Adhes" user "F.Adhesive")
		(11 "B.Adhes" user "B.Adhesive")
		(13 "F.Paste" user)
		(15 "B.Paste" user)
		(5 "F.SilkS" user "F.Silkscreen")
		(7 "B.SilkS" user "B.Silkscreen")
		(1 "F.Mask" user)
		(3 "B.Mask" user)
		(17 "Dwgs.User" user "User.Drawings")
		(19 "Cmts.User" user "User.Comments")
		(21 "Eco1.User" user "User.Eco1")
		(23 "Eco2.User" user "User.Eco2")
		(25 "Edge.Cuts" user)
		(27 "Margin" user)
		(31 "F.CrtYd" user "F.Courtyard")
		(29 "B.CrtYd" user "B.Courtyard")
		(35 "F.Fab" user)
		(33 "B.Fab" user)
	)
	(footprint "antmicro-footprints:C_0402_1005Metric"
		(layer "B.Cu")
		(at 210.577 124.3878)
		(descr "Capacitor SMD 0402")
		(tags "capacitor SMD 0402")
		(property "Reference" "C257"
			(at -3.727 2.6372 0)
			(layer "B.SilkS")
			(effects
				(font
					(size 0.7 0.7)
					(thickness 0.15)
				)
				(justify right bottom mirror)
			)
		)
		(property "Value" "C_100n_0402"
			(at -1.022927 -2.155213 0)
			(layer "B.Fab")
			(hide yes)
			(effects
				(font
					(size 0.7 0.7)
					(thickness 0.15)
				)
				(justify right bottom mirror)
			)
		)
		(property "Datasheet" "https://www.murata.com/products/productdetail?partno=GRM155R61H104KE14%23"
			(at 0 0 0)
			(layer "F.Fab")
			(hide yes)
			(effects
				(font
					(size 1.27 1.27)
					(thickness 0.15)
				)
			)
		)
		(property "Description" "SMD Multilayer Ceramic Capacitor, 0.1 µF, 50 V, 0402 [1005 Metric], ± 10%, X5R, GRM Series"
			(at 0 0 0)
			(layer "F.Fab")
			(hide yes)
			(effects
				(font
					(size 1.27 1.27)
					(thickness 0.15)
				)
			)
		)
		(property "Author" "Antmicro"
			(at 0 0 0)
			(layer "B.Fab")
			(hide yes)
			(effects
				(font
					(size 1 1)
					(thickness 0.15)
				)
				(justify mirror)
			)
		)
		(property "Dielectric" "X5R"
			(at 0 0 0)
			(layer "B.Fab")
			(hide yes)
			(effects
				(font
					(size 1 1)
					(thickness 0.15)
				)
				(justify mirror)
			)
		)
		(property "License" "Apache-2.0"
			(at 0 0 0)
			(layer "B.Fab")
			(hide yes)
			(effects
				(font
					(size 1 1)
					(thickness 0.15)
				)
				(justify mirror)
			)
		)
		(property "MPN" "GRM155R61H104KE14D"
			(at 0 0 0)
			(layer "B.Fab")
			(hide yes)
			(effects
				(font
					(size 1 1)
					(thickness 0.15)
				)
				(justify mirror)
			)
		)
		(property "Manufacturer" "Murata"
			(at 0 0 0)
			(layer "B.Fab")
			(hide yes)
			(effects
				(font
					(size 1 1)
					(thickness 0.15)
				)
				(justify mirror)
			)
		)
		(property "Public" ""
			(at 0 0 0)
			(layer "B.Fab")
			(hide yes)
			(effects
				(font
					(size 1 1)
					(thickness 0.15)
				)
				(justify mirror)
			)
		)
		(property "Val" "100n"
			(at 0 0 0)
			(layer "B.Fab")
			(hide yes)
			(effects
				(font
					(size 1 1)
					(thickness 0.15)
				)
				(justify mirror)
			)
		)
		(property "Voltage" "50V"
			(at 0 0 0)
			(layer "B.Fab")
			(hide yes)
			(effects
				(font
					(size 1 1)
					(thickness 0.15)
				)
				(justify mirror)
			)
		)
		(sheetname "/Ethernet/")
		(sheetfile "ethernet.kicad_sch")
		(attr smd)
		(fp_rect
			(start -0.925 0.47)
			(end 0.925 -0.47)
			(stroke
				(width 0.05)
				(type default)
			)
			(fill no)
			(layer "B.CrtYd")
		)
		(fp_line
			(start -0.494 -0.248)
			(end -0.494 0.25)
			(stroke
				(width 0.15)
				(type solid)
			)
			(layer "B.Fab")
		)
		(fp_line
			(start -0.494 0.25)
			(end 0.504 0.25)
			(stroke
				(width 0.15)
				(type solid)
			)
			(layer "B.Fab")
		)
		(fp_line
			(start 0.504 -0.248)
			(end -0.494 -0.248)
			(stroke
				(width 0.15)
				(type solid)
			)
			(layer "B.Fab")
		)
		(fp_line
			(start 0.504 0.25)
			(end 0.504 -0.248)
			(stroke
				(width 0.15)
				(type solid)
			)
			(layer "B.Fab")
		)
		(fp_text user "${REFERENCE}"
			(at -0.939 -4.599 180)
			(layer "B.Fab")
			(effects
				(font
					(size 0.7 0.7)
					(thickness 0.15)
				)
				(justify left bottom mirror)
			)
		)
		(fp_text user "License: Apache-2.0"
			(at -0.939 -5.799 180)
			(layer "B.Fab")
			(effects
				(font
					(size 0.7 0.7)
					(thickness 0.15)
				)
				(justify left bottom mirror)
			)
		)
		(fp_text user "Author: Antmicro"
			(at -0.939 -3.399 180)
			(layer "B.Fab")
			(effects
				(font
					(size 0.7 0.7)
					(thickness 0.15)
				)
				(justify left bottom mirror)
			)
		)
		(pad "1" smd roundrect
			(at -0.48 0)
			(size 0.59 0.64)
			(layers "B.Cu" "B.Mask" "B.Paste")
			(roundrect_rratio 0.25)
			(net 41 "/Ethernet/SGMII.RX0_N")
			(pintype "passive")
		)
		(pad "2" smd roundrect
			(at 0.48 0)
			(size 0.59 0.64)
			(layers "B.Cu" "B.Mask" "B.Paste")
			(roundrect_rratio 0.25)
			(net 166 "/Ethernet/SGMII_SO_N")
			(pintype "passive")
		)
	)
	(footprint "antmicro-footprints:C_0402_1005Metric"
		(layer "B.Cu")
		(at 180 125.1 90)
		(descr "Capacitor SMD 0402")
		(tags "capacitor SMD 0402")
		(property "Reference" "C163"
			(at 1.148 1.356 270)
			(layer "B.SilkS")
			(effects
				(font
					(size 0.7 0.7)
					(thickness 0.15)
				)
				(justify left bottom mirror)
			)
		)
		(property "Value" "C_1u_0402"
			(at -1.022927 -2.155213 270)
			(layer "B.Fab")
			(hide yes)
			(effects
				(font
					(size 0.7 0.7)
					(thickness 0.15)
				)
				(justify left bottom mirror)
			)
		)
		(property "Datasheet" "https://product.tdk.com/en/search/capacitor/ceramic/mlcc/info?part_no=C1005X6S1A105K050BC"
			(at 0 0 90)
			(layer "F.Fab")
			(hide yes)
			(effects
				(font
					(size 1.27 1.27)
					(thickness 0.15)
				)
			)
		)
		(property "Description" "SMD Multilayer Ceramic Capacitor, 1 µF, 10 V, 0402 [1005 Metric], ± 10%, X6S, C"
			(at 0 0 90)
			(layer "F.Fab")
			(hide yes)
			(effects
				(font
					(size 1.27 1.27)
					(thickness 0.15)
				)
			)
		)
		(property "Author" "Antmicro"
			(at 305.1 -54.9 0)
			(layer "B.Fab")
			(hide yes)
			(effects
				(font
					(size 1 1)
					(thickness 0.15)
				)
				(justify mirror)
			)
		)
		(property "Dielectric" "X5R"
			(at 305.1 -54.9 0)
			(layer "B.Fab")
			(hide yes)
			(effects
				(font
					(size 1 1)
					(thickness 0.15)
				)
				(justify mirror)
			)
		)
		(property "License" "Apache-2.0"
			(at 305.1 -54.9 0)
			(layer "B.Fab")
			(hide yes)
			(effects
				(font
					(size 1 1)
					(thickness 0.15)
				)
				(justify mirror)
			)
		)
		(property "MPN" "C1005X6S1A105K050BC"
			(at 305.1 -54.9 0)
			(layer "B.Fab")
			(hide yes)
			(effects
				(font
					(size 1 1)
					(thickness 0.15)
				)
				(justify mirror)
			)
		)
		(property "Manufacturer" "TDK"
			(at 305.1 -54.9 0)
			(layer "B.Fab")
			(hide yes)
			(effects
				(font
					(size 1 1)
					(thickness 0.15)
				)
				(justify mirror)
			)
		)
		(property "Public" ""
			(at 305.1 -54.9 0)
			(layer "B.Fab")
			(hide yes)
			(effects
				(font
					(size 1 1)
					(thickness 0.15)
				)
				(justify mirror)
			)
		)
		(property "Val" "1u"
			(at 305.1 -54.9 0)
			(layer "B.Fab")
			(hide yes)
			(effects
				(font
					(size 1 1)
					(thickness 0.15)
				)
				(justify mirror)
			)
		)
		(property "Voltage" "16V"
			(at 305.1 -54.9 0)
			(layer "B.Fab")
			(hide yes)
			(effects
				(font
					(size 1 1)
					(thickness 0.15)
				)
				(justify mirror)
			)
		)
		(sheetname "/LPDDR4/")
		(sheetfile "lpddr.kicad_sch")
		(attr smd)
		(fp_rect
			(start -0.925 0.47)
			(end 0.925 -0.47)
			(stroke
				(width 0.05)
				(type default)
			)
			(fill no)
			(layer "B.CrtYd")
		)
		(fp_line
			(start 0.504 -0.248)
			(end -0.494 -0.248)
			(stroke
				(width 0.15)
				(type solid)
			)
			(layer "B.Fab")
		)
		(fp_line
			(start -0.494 -0.248)
			(end -0.494 0.25)
			(stroke
				(width 0.15)
				(type solid)
			)
			(layer "B.Fab")
		)
		(fp_line
			(start 0.504 0.25)
			(end 0.504 -0.248)
			(stroke
				(width 0.15)
				(type solid)
			)
			(layer "B.Fab")
		)
		(fp_line
			(start -0.494 0.25)
			(end 0.504 0.25)
			(stroke
				(width 0.15)
				(type solid)
			)
			(layer "B.Fab")
		)
		(fp_text user "License: Apache-2.0"
			(at -0.939 -5.799 270)
			(layer "B.Fab")
			(effects
				(font
					(size 0.7 0.7)
					(thickness 0.15)
				)
				(justify left bottom mirror)
			)
		)
		(fp_text user "Author: Antmicro"
			(at -0.939 -3.399 270)
			(layer "B.Fab")
			(effects
				(font
					(size 0.7 0.7)
					(thickness 0.15)
				)
				(justify left bottom mirror)
			)
		)
		(fp_text user "${REFERENCE}"
			(at -0.939 -4.599 270)
			(layer "B.Fab")
			(effects
				(font
					(size 0.7 0.7)
					(thickness 0.15)
				)
				(justify left bottom mirror)
			)
		)
		(pad "1" smd roundrect
			(at -0.48 0 90)
			(size 0.59 0.64)
			(layers "B.Cu" "B.Mask" "B.Paste")
			(roundrect_rratio 0.25)
			(net 417 "GND")
			(pintype "passive")
		)
		(pad "2" smd roundrect
			(at 0.48 0 90)
			(size 0.59 0.64)
			(layers "B.Cu" "B.Mask" "B.Paste")
			(roundrect_rratio 0.25)
			(net 2 "+1V1")
			(pintype "passive")
		)
	)
	(footprint "antmicro-footprints:C_0402_1005Metric"
		(layer "B.Cu")
		(at 195.72 145.3)
		(descr "Capacitor SMD 0402")
		(tags "capacitor SMD 0402")
		(property "Reference" "C226"
			(at -1.645 -0.425 0)
			(layer "B.SilkS")
			(effects
				(font
					(size 0.7 0.7)
					(thickness 0.15)
				)
				(justify right bottom mirror)
			)
		)
		(property "Value" "C_4u7_0402"
			(at -1.022927 -2.155213 0)
			(layer "B.Fab")
			(hide yes)
			(effects
				(font
					(size 0.7 0.7)
					(thickness 0.15)
				)
				(justify right bottom mirror)
			)
		)
		(property "Datasheet" "https://www.murata.com/products/productdetail?partno=GRM155R61A475MEAA%23"
			(at 0 0 0)
			(layer "F.Fab")
			(hide yes)
			(effects
				(font
					(size 1.27 1.27)
					(thickness 0.15)
				)
			)
		)
		(property "Description" "SMD Multilayer Ceramic Capacitor, 4.7 µF, 10 V, 0402 [1005 Metric], ± 20%, X5R, GRM Series"
			(at 0 0 0)
			(layer "F.Fab")
			(hide yes)
			(effects
				(font
					(size 1.27 1.27)
					(thickness 0.15)
				)
			)
		)
		(property "Author" "Antmicro"
			(at 0 0 0)
			(layer "B.Fab")
			(hide yes)
			(effects
				(font
					(size 1 1)
					(thickness 0.15)
				)
				(justify mirror)
			)
		)
		(property "Dielectric" ""
			(at 0 0 0)
			(layer "B.Fab")
			(hide yes)
			(effects
				(font
					(size 1 1)
					(thickness 0.15)
				)
				(justify mirror)
			)
		)
		(property "License" "Apache-2.0"
			(at 0 0 0)
			(layer "B.Fab")
			(hide yes)
			(effects
				(font
					(size 1 1)
					(thickness 0.15)
				)
				(justify mirror)
			)
		)
		(property "MPN" "GRM155R61A475MEAAD"
			(at 0 0 0)
			(layer "B.Fab")
			(hide yes)
			(effects
				(font
					(size 1 1)
					(thickness 0.15)
				)
				(justify mirror)
			)
		)
		(property "Manufacturer" "Murata"
			(at 0 0 0)
			(layer "B.Fab")
			(hide yes)
			(effects
				(font
					(size 1 1)
					(thickness 0.15)
				)
				(justify mirror)
			)
		)
		(property "Public" ""
			(at 0 0 0)
			(layer "B.Fab")
			(hide yes)
			(effects
				(font
					(size 1 1)
					(thickness 0.15)
				)
				(justify mirror)
			)
		)
		(property "Val" "4u7"
			(at 0 0 0)
			(layer "B.Fab")
			(hide yes)
			(effects
				(font
					(size 1 1)
					(thickness 0.15)
				)
				(justify mirror)
			)
		)
		(property "Voltage" ""
			(at 0 0 0)
			(layer "B.Fab")
			(hide yes)
			(effects
				(font
					(size 1 1)
					(thickness 0.15)
				)
				(justify mirror)
			)
		)
		(sheetname "/HDMI/")
		(sheetfile "hdmi.kicad_sch")
		(attr smd)
		(fp_rect
			(start -0.925 0.47)
			(end 0.925 -0.47)
			(stroke
				(width 0.05)
				(type default)
			)
			(fill no)
			(layer "B.CrtYd")
		)
		(fp_line
			(start -0.494 -0.248)
			(end -0.494 0.25)
			(stroke
				(width 0.15)
				(type solid)
			)
			(layer "B.Fab")
		)
		(fp_line
			(start -0.494 0.25)
			(end 0.504 0.25)
			(stroke
				(width 0.15)
				(type solid)
			)
			(layer "B.Fab")
		)
		(fp_line
			(start 0.504 -0.248)
			(end -0.494 -0.248)
			(stroke
				(width 0.15)
				(type solid)
			)
			(layer "B.Fab")
		)
		(fp_line
			(start 0.504 0.25)
			(end 0.504 -0.248)
			(stroke
				(width 0.15)
				(type solid)
			)
			(layer "B.Fab")
		)
		(fp_text user "Author: Antmicro"
			(at -0.939 -3.399 180)
			(layer "B.Fab")
			(effects
				(font
					(size 0.7 0.7)
					(thickness 0.15)
				)
				(justify left bottom mirror)
			)
		)
		(fp_text user "License: Apache-2.0"
			(at -0.939 -5.799 180)
			(layer "B.Fab")
			(effects
				(font
					(size 0.7 0.7)
					(thickness 0.15)
				)
				(justify left bottom mirror)
			)
		)
		(fp_text user "${REFERENCE}"
			(at -0.939 -4.599 180)
			(layer "B.Fab")
			(effects
				(font
					(size 0.7 0.7)
					(thickness 0.15)
				)
				(justify left bottom mirror)
			)
		)
		(pad "1" smd roundrect
			(at -0.48 0)
			(size 0.59 0.64)
			(layers "B.Cu" "B.Mask" "B.Paste")
			(roundrect_rratio 0.25)
			(net 417 "GND")
			(pintype "passive")
		)
		(pad "2" smd roundrect
			(at 0.48 0)
			(size 0.59 0.64)
			(layers "B.Cu" "B.Mask" "B.Paste")
			(roundrect_rratio 0.25)
			(net 554 "Net-(U15-CEXT)")
			(pintype "passive")
		)
	)
	(footprint "antmicro-footprints:C_0402_1005Metric"
		(layer "B.Cu")
		(at 179.1 144.0125)
		(descr "Capacitor SMD 0402")
		(tags "capacitor SMD 0402")
		(property "Reference" "C104"
			(at 1.53 1.7775 315)
			(layer "B.SilkS")
			(effects
				(font
					(size 0.7 0.7)
					(thickness 0.15)
				)
				(justify right bottom mirror)
			)
		)
		(property "Value" "C_10u_10V_0402"
			(at -1.022927 -2.155213 0)
			(layer "B.Fab")
			(hide yes)
			(effects
				(font
					(size 0.7 0.7)
					(thickness 0.15)
				)
				(justify right bottom mirror)
			)
		)
		(property "Datasheet" "https://www.murata.com/products/productdetail?partno=GRM155R61A106ME11%23"
			(at 0 0 0)
			(layer "F.Fab")
			(hide yes)
			(effects
				(font
					(size 1.27 1.27)
					(thickness 0.15)
				)
			)
		)
		(property "Description" "Multilayer Ceramic Capacitors MLCC - SMD/SMT 10 uF 10 VDC 20% 0402 X5R"
			(at 0 0 0)
			(layer "F.Fab")
			(hide yes)
			(effects
				(font
					(size 1.27 1.27)
					(thickness 0.15)
				)
			)
		)
		(property "Author" "Antmicro"
			(at 0 0 0)
			(layer "B.Fab")
			(hide yes)
			(effects
				(font
					(size 1 1)
					(thickness 0.15)
				)
				(justify mirror)
			)
		)
		(property "Dielectric" "X5R"
			(at 0 0 0)
			(layer "B.Fab")
			(hide yes)
			(effects
				(font
					(size 1 1)
					(thickness 0.15)
				)
				(justify mirror)
			)
		)
		(property "License" "Apache-2.0"
			(at 0 0 0)
			(layer "B.Fab")
			(hide yes)
			(effects
				(font
					(size 1 1)
					(thickness 0.15)
				)
				(justify mirror)
			)
		)
		(property "MPN" "GRM155R61A106ME11D"
			(at 0 0 0)
			(layer "B.Fab")
			(hide yes)
			(effects
				(font
					(size 1 1)
					(thickness 0.15)
				)
				(justify mirror)
			)
		)
		(property "Manufacturer" "Murata"
			(at 0 0 0)
			(layer "B.Fab")
			(hide yes)
			(effects
				(font
					(size 1 1)
					(thickness 0.15)
				)
				(justify mirror)
			)
		)
		(property "Public" ""
			(at 0 0 0)
			(layer "B.Fab")
			(hide yes)
			(effects
				(font
					(size 1 1)
					(thickness 0.15)
				)
				(justify mirror)
			)
		)
		(property "Val" "10u"
			(at 0 0 0)
			(layer "B.Fab")
			(hide yes)
			(effects
				(font
					(size 1 1)
					(thickness 0.15)
				)
				(justify mirror)
			)
		)
		(property "Voltage" "10V"
			(at 0 0 0)
			(layer "B.Fab")
			(hide yes)
			(effects
				(font
					(size 1 1)
					(thickness 0.15)
				)
				(justify mirror)
			)
		)
		(sheetname "/Supply/")
		(sheetfile "supply.kicad_sch")
		(attr smd)
		(fp_rect
			(start -0.925 0.47)
			(end 0.925 -0.47)
			(stroke
				(width 0.05)
				(type default)
			)
			(fill no)
			(layer "B.CrtYd")
		)
		(fp_line
			(start -0.494 -0.248)
			(end -0.494 0.25)
			(stroke
				(width 0.15)
				(type solid)
			)
			(layer "B.Fab")
		)
		(fp_line
			(start -0.494 0.25)
			(end 0.504 0.25)
			(stroke
				(width 0.15)
				(type solid)
			)
			(layer "B.Fab")
		)
		(fp_line
			(start 0.504 -0.248)
			(end -0.494 -0.248)
			(stroke
				(width 0.15)
				(type solid)
			)
			(layer "B.Fab")
		)
		(fp_line
			(start 0.504 0.25)
			(end 0.504 -0.248)
			(stroke
				(width 0.15)
				(type solid)
			)
			(layer "B.Fab")
		)
		(fp_text user "${REFERENCE}"
			(at -0.939 -4.599 180)
			(layer "B.Fab")
			(effects
				(font
					(size 0.7 0.7)
					(thickness 0.15)
				)
				(justify left bottom mirror)
			)
		)
		(fp_text user "License: Apache-2.0"
			(at -0.939 -5.799 180)
			(layer "B.Fab")
			(effects
				(font
					(size 0.7 0.7)
					(thickness 0.15)
				)
				(justify left bottom mirror)
			)
		)
		(fp_text user "Author: Antmicro"
			(at -0.939 -3.399 180)
			(layer "B.Fab")
			(effects
				(font
					(size 0.7 0.7)
					(thickness 0.15)
				)
				(justify left bottom mirror)
			)
		)
		(pad "1" smd roundrect
			(at -0.48 0)
			(size 0.59 0.64)
			(layers "B.Cu" "B.Mask" "B.Paste")
			(roundrect_rratio 0.25)
			(net 417 "GND")
			(pintype "passive")
		)
		(pad "2" smd roundrect
			(at 0.48 0)
			(size 0.59 0.64)
			(layers "B.Cu" "B.Mask" "B.Paste")
			(roundrect_rratio 0.25)
			(net 633 "Net-(U7-OUT4)")
			(pintype "passive")
		)
	)
)
